(kicad_pcb
	(version 20260206)
	(generator "pcbnew")
	(generator_version "10.0")
	(general
		(thickness 1.6)
		(legacy_teardrops no)
	)
	(paper "A4")
	(title_block
		(title "03242023_DA0F0TMBIJ0_F0T_Motherboard_J_brd_V01_OCP.brd")
		(comment 1 "Grand Teton / footprints 647-650 of 6105")
	)
	(layers
		(0 "F.Cu" signal "TOP")
		(4 "In1.Cu" signal "GND")
		(6 "In2.Cu" signal "IN1")
		(8 "In3.Cu" signal "GND1")
		(10 "In4.Cu" signal "IN2")
		(12 "In5.Cu" signal "GND2")
		(14 "In6.Cu" signal "IN3")
		(16 "In7.Cu" signal "GND3")
		(18 "In8.Cu" signal "VCC")
		(20 "In9.Cu" signal "VCC1")
		(22 "In10.Cu" signal "GND4")
		(24 "In11.Cu" signal "IN4")
		(26 "In12.Cu" signal "GND5")
		(28 "In13.Cu" signal "IN5")
		(30 "In14.Cu" signal "GND6")
		(32 "In15.Cu" signal "IN6")
		(34 "In16.Cu" signal "GND7")
		(2 "B.Cu" signal "BOTTOM")
		(9 "F.Adhes" user "F.Adhesive")
		(11 "B.Adhes" user "B.Adhesive")
		(13 "F.Paste" user "Package Geometry/Pastemask Top")
		(15 "B.Paste" user "Package Geometry/Pastemask Bottom")
		(5 "F.SilkS" user "Ref Des/Silkscreen Top")
		(7 "B.SilkS" user "Ref Des/Silkscreen Bottom")
		(1 "F.Mask" user "Board Geometry/Soldermask Top")
		(3 "B.Mask" user "Board Geometry/Soldermask Bottom")
		(17 "Dwgs.User" user "User.Drawings")
		(19 "Cmts.User" user "User.Comments")
		(21 "Eco1.User" user "User.Eco1")
		(23 "Eco2.User" user "User.Eco2")
		(25 "Edge.Cuts" user "Board Geometry/Outline")
		(27 "Margin" user)
		(31 "F.CrtYd" user "Package Geometry/Place Bound Top")
		(29 "B.CrtYd" user "Package Geometry/Place Bound Bottom")
		(35 "F.Fab" user "Ref Des/Assembly Top")
		(33 "B.Fab" user "Ref Des/Assembly Bottom")
	)
	(footprint ""
		(layer "F.Cu")
		(at 105.158286 -333.716122)
		(property "Reference" "PU30_P1_2"
			(at -2.670048 -6.321298 0)
			(unlocked yes)
			(layer "F.SilkS")
			(effects
				(font
					(size 0.7874 0.5842)
					(thickness 0.1524)
				)
				(justify left)
			)
		)
		(property "Value" ""
			(at 0 0 0)
			(layer "F.Fab")
			(effects
				(font
					(size 1.27 1.27)
				)
			)
		)
		(duplicate_pad_numbers_are_jumpers no)
		(fp_line
			(start -2.500122 -2.999994)
			(end -2.24409 -2.999994)
			(stroke
				(width 0.1524)
				(type default)
			)
			(layer "F.SilkS")
		)
		(fp_line
			(start -2.500122 -2.529078)
			(end -2.500122 -2.999994)
			(stroke
				(width 0.1524)
				(type default)
			)
			(layer "F.SilkS")
		)
		(fp_line
			(start -2.500122 0.6604)
			(end -2.500122 0.229108)
			(stroke
				(width 0.1524)
				(type default)
			)
			(layer "F.SilkS")
		)
		(fp_line
			(start -2.500122 2.999994)
			(end -2.500122 2.339594)
			(stroke
				(width 0.1524)
				(type default)
			)
			(layer "F.SilkS")
		)
		(fp_line
			(start -2.2987 2.999994)
			(end -2.500122 2.999994)
			(stroke
				(width 0.1524)
				(type default)
			)
			(layer "F.SilkS")
		)
		(fp_line
			(start 2.31394 -2.999994)
			(end 2.500122 -2.999994)
			(stroke
				(width 0.1524)
				(type default)
			)
			(layer "F.SilkS")
		)
		(fp_line
			(start 2.500122 -2.999994)
			(end 2.500122 -2.44348)
			(stroke
				(width 0.1524)
				(type default)
			)
			(layer "F.SilkS")
		)
		(fp_line
			(start 2.500122 2.339594)
			(end 2.500122 2.999994)
			(stroke
				(width 0.1524)
				(type default)
			)
			(layer "F.SilkS")
		)
		(fp_line
			(start 2.500122 2.999994)
			(end 2.2987 2.999994)
			(stroke
				(width 0.1524)
				(type default)
			)
			(layer "F.SilkS")
		)
		(fp_poly
			(pts
				(xy -2.156714 -3.626612) (xy -2.664714 -2.610612) (xy -3.172714 -3.626612)
			)
			(stroke
				(width 0)
				(type default)
			)
			(fill yes)
			(layer "F.SilkS")
		)
		(fp_line
			(start -2.500122 -2.999994)
			(end 2.500122 -2.999994)
			(stroke
				(width 0.1)
				(type default)
			)
			(layer "F.Fab")
		)
		(fp_line
			(start -2.500122 2.999994)
			(end -2.500122 -2.999994)
			(stroke
				(width 0.1)
				(type default)
			)
			(layer "F.Fab")
		)
		(fp_line
			(start 2.500122 -2.999994)
			(end 2.500122 2.999994)
			(stroke
				(width 0.1)
				(type default)
			)
			(layer "F.Fab")
		)
		(fp_line
			(start 2.500122 2.999994)
			(end -2.500122 2.999994)
			(stroke
				(width 0.1)
				(type default)
			)
			(layer "F.Fab")
		)
		(fp_poly
			(pts
				(xy -4.218432 -2.783078) (xy -4.218432 -1.767078) (xy -3.202432 -2.275078)
			)
			(stroke
				(width 0)
				(type default)
			)
			(fill yes)
			(layer "F.Fab")
		)
		(pad "1" smd rect
			(at -2.400046 -2.275078 90)
			(size 0.2286 0.6096)
			(layers "F.Cu" "F.Mask" "F.Paste")
			(net "PVCCIN_CPU1_VOS2")
		)
		(pad "2" smd rect
			(at -2.400046 -1.82499 90)
			(size 0.2286 0.6096)
			(layers "F.Cu" "F.Mask" "F.Paste")
			(net "GND")
		)
		(pad "3" smd rect
			(at -2.400046 -1.374902 90)
			(size 0.2286 0.6096)
			(layers "F.Cu" "F.Mask" "F.Paste")
			(net "PVCCIN_CPU1_VDD2")
		)
		(pad "4" smd rect
			(at -2.400046 -0.925068 90)
			(size 0.2286 0.6096)
			(layers "F.Cu" "F.Mask" "F.Paste")
			(net "PVCCIN_CPU1_PVCC")
		)
		(pad "5" smd rect
			(at -2.400046 -0.47498 90)
			(size 0.2286 0.6096)
			(layers "F.Cu" "F.Mask" "F.Paste")
			(net "GND")
		)
		(pad "6" smd rect
			(at -2.400046 -0.024892 90)
			(size 0.2286 0.6096)
			(layers "F.Cu" "F.Mask" "F.Paste")
			(net "Net_8523")
		)
		(pad "7_9-20_24" smd circle
			(at 0 1.150112 90)
			(size 0 0)
			(layers "F.Cu" "F.Mask" "F.Paste")
			(net "GND")
		)
		(pad "10_19" smd rect
			(at 0 2.899918 90)
			(size 0.6096 4.318)
			(layers "F.Cu" "F.Mask" "F.Paste")
			(net "SW_PVCCIN_CPU1_SW2")
		)
		(pad "25_29" smd rect
			(at 1.549908 -1.279906 270)
			(size 2.0574 2.3114)
			(layers "F.Cu" "F.Mask" "F.Paste")
			(net "SW_P12V_PVCCIN_CPU1_FLT")
		)
		(pad "30" smd rect
			(at 2.05994 -2.899918)
			(size 0.2286 0.6096)
			(layers "F.Cu" "F.Mask" "F.Paste")
			(net "SW_P12V_PVCCIN_CPU1_FLT")
		)
		(pad "31" smd rect
			(at 1.610106 -2.899918)
			(size 0.2286 0.6096)
			(layers "F.Cu" "F.Mask" "F.Paste")
			(net "Net_8524")
		)
		(pad "32" smd rect
			(at 1.160018 -2.899918)
			(size 0.2286 0.6096)
			(layers "F.Cu" "F.Mask" "F.Paste")
			(net "SW_PVCCIN_CPU1_BOOTR2")
		)
		(pad "33" smd rect
			(at 0.70993 -2.899918)
			(size 0.2286 0.6096)
			(layers "F.Cu" "F.Mask" "F.Paste")
			(net "SW_PVCCIN_CPU1_BOOT2")
		)
		(pad "34" smd rect
			(at 0.260096 -2.899918)
			(size 0.2286 0.6096)
			(layers "F.Cu" "F.Mask" "F.Paste")
			(net "PVCCIN_CPU1_PWM2")
		)
		(pad "35" smd rect
			(at -0.189992 -2.899918)
			(size 0.2286 0.6096)
			(layers "F.Cu" "F.Mask" "F.Paste")
			(net "PVCCIN_CPU1_VDD2")
		)
		(pad "36" smd rect
			(at -0.64008 -2.899918)
			(size 0.2286 0.6096)
			(layers "F.Cu" "F.Mask" "F.Paste")
			(net "PVCCIN_CPU1_ATSEN")
		)
		(pad "37" smd rect
			(at -1.089914 -2.899918)
			(size 0.2286 0.6096)
			(layers "F.Cu" "F.Mask" "F.Paste")
			(net "PVCCIN_CPU1_LSET2")
		)
		(pad "38" smd rect
			(at -1.540002 -2.899918)
			(size 0.2286 0.6096)
			(layers "F.Cu" "F.Mask" "F.Paste")
			(net "PVCCIN_CPU1_IMON2")
		)
		(pad "39" smd rect
			(at -1.99009 -2.899918)
			(size 0.2286 0.6096)
			(layers "F.Cu" "F.Mask" "F.Paste")
			(net "PVCCIN_CPU1_VREF")
		)
		(pad "40" smd rect
			(at -0.87503 -1.27508)
			(size 1.7526 1.9558)
			(layers "F.Cu" "F.Mask" "F.Paste")
			(net "GND")
		)
		(pad "41" smd rect
			(at -1.525016 0.249936 270)
			(size 0.3048 0.4572)
			(layers "F.Cu" "F.Mask" "F.Paste")
			(net "Net_8522")
		)
		(zone
			(layer "F.Cu")
			(hatch none 0.5)
			(connect_pads
				(clearance 0)
			)
			(min_thickness 0.25)
			(keepout
				(tracks not_allowed)
				(vias allowed)
				(pads allowed)
				(copperpour not_allowed)
				(footprints allowed)
			)
			(placement
				(enabled no)
				(sheetname "")
			)
			(fill
				(thermal_gap 0.5)
				(thermal_bridge_width 0.5)
				(island_removal_mode 0)
			)
			(polygon
				(pts
					(xy 102.658164 -330.716128) (xy 102.658164 -331.465428) (xy 107.658408 -331.465428) (xy 107.658408 -330.716128)
					(xy 107.368086 -330.716128) (xy 107.368086 -331.171804) (xy 102.948486 -331.171804) (xy 102.948486 -330.716128)
				)
			)
		)
		(zone
			(layer "F.Cu")
			(hatch none 0.5)
			(connect_pads
				(clearance 0)
			)
			(min_thickness 0.25)
			(keepout
				(tracks not_allowed)
				(vias allowed)
				(pads allowed)
				(copperpour not_allowed)
				(footprints allowed)
			)
			(placement
				(enabled no)
				(sheetname "")
			)
			(fill
				(thermal_gap 0.5)
				(thermal_bridge_width 0.5)
				(island_removal_mode 0)
			)
			(polygon
				(pts
					(xy 103.11384 -334.040988) (xy 103.356156 -334.040988) (xy 103.356156 -333.962502) (xy 104.13238 -333.962502)
					(xy 104.13238 -333.632048) (xy 104.207564 -333.632048) (xy 104.207564 -332.966822) (xy 102.658164 -332.966822)
					(xy 102.658164 -333.423514) (xy 103.35387 -333.423514) (xy 103.35387 -333.262986) (xy 103.91267 -333.262986)
					(xy 103.91267 -333.669386) (xy 103.35387 -333.669386) (xy 103.35387 -333.448914) (xy 102.658164 -333.448914)
					(xy 102.658164 -333.575914) (xy 103.11384 -333.575914)
				)
			)
		)
	)
	(footprint ""
		(layer "F.Cu")
		(at 58.578496 -70.78599)
		(property "Reference" "D72"
			(at -31.785306 50.178462 90)
			(unlocked yes)
			(layer "F.SilkS")
			(effects
				(font
					(size 0.635 0.4064)
					(thickness 0.1524)
				)
				(justify left)
			)
		)
		(property "Value" ""
			(at 0 0 0)
			(layer "F.Fab")
			(effects
				(font
					(size 1.27 1.27)
				)
			)
		)
		(duplicate_pad_numbers_are_jumpers no)
		(fp_line
			(start -0.90678 0.4826)
			(end -0.90678 -0.4699)
			(stroke
				(width 0.1524)
				(type default)
			)
			(layer "F.SilkS")
		)
		(fp_line
			(start -0.89408 -0.4826)
			(end 0.90678 -0.4826)
			(stroke
				(width 0.1524)
				(type default)
			)
			(layer "F.SilkS")
		)
		(fp_line
			(start -0.79248 -0.4826)
			(end 1.03378 -0.4826)
			(stroke
				(width 0.1524)
				(type default)
			)
			(layer "F.SilkS")
		)
		(fp_line
			(start -0.64008 -0.4826)
			(end 1.16078 -0.4826)
			(stroke
				(width 0.1524)
				(type default)
			)
			(layer "F.SilkS")
		)
		(fp_line
			(start 0.90678 -0.4826)
			(end 0.90678 0.4826)
			(stroke
				(width 0.1524)
				(type default)
			)
			(layer "F.SilkS")
		)
		(fp_line
			(start 0.90678 0.4826)
			(end -0.90678 0.4826)
			(stroke
				(width 0.1524)
				(type default)
			)
			(layer "F.SilkS")
		)
		(fp_line
			(start 1.03378 -0.4826)
			(end 1.03378 0.4826)
			(stroke
				(width 0.1524)
				(type default)
			)
			(layer "F.SilkS")
		)
		(fp_line
			(start 1.03378 0.4826)
			(end -0.79248 0.4826)
			(stroke
				(width 0.1524)
				(type default)
			)
			(layer "F.SilkS")
		)
		(fp_line
			(start 1.16078 -0.4826)
			(end 1.16078 0.4826)
			(stroke
				(width 0.1524)
				(type default)
			)
			(layer "F.SilkS")
		)
		(fp_line
			(start 1.16078 0.4826)
			(end -0.64008 0.4826)
			(stroke
				(width 0.1524)
				(type default)
			)
			(layer "F.SilkS")
		)
		(fp_line
			(start -0.499872 -0.249936)
			(end 0.499872 -0.249936)
			(stroke
				(width 0.1)
				(type default)
			)
			(layer "F.Fab")
		)
		(fp_line
			(start -0.499872 0.249936)
			(end -0.499872 -0.249936)
			(stroke
				(width 0.1)
				(type default)
			)
			(layer "F.Fab")
		)
		(fp_line
			(start 0.499872 -0.249936)
			(end 0.499872 0.249936)
			(stroke
				(width 0.1)
				(type default)
			)
			(layer "F.Fab")
		)
		(fp_line
			(start 0.499872 0.249936)
			(end -0.499872 0.249936)
			(stroke
				(width 0.1)
				(type default)
			)
			(layer "F.Fab")
		)
		(pad "A" smd rect
			(at -0.47498 0)
			(size 0.6096 0.7112)
			(layers "F.Cu" "F.Mask" "F.Paste")
			(net "LED_RST_PLD_CPU1_DRAM_GH_N")
		)
		(pad "C" smd rect
			(at 0.47498 0)
			(size 0.6096 0.7112)
			(layers "F.Cu" "F.Mask" "F.Paste")
			(net "LED_RST_PLD_CPU1_DRAM_GH_N_D")
		)
	)
	(footprint ""
		(layer "F.Cu")
		(at 121.984008 -360.043222 90)
		(property "Reference" "PR1339"
			(at 0 0 90)
			(layer "F.SilkS")
			(hide yes)
			(effects
				(font
					(size 1.27 1.27)
				)
			)
		)
		(property "Value" ""
			(at 0 0 90)
			(layer "F.Fab")
			(effects
				(font
					(size 1.27 1.27)
				)
			)
		)
		(duplicate_pad_numbers_are_jumpers no)
		(fp_line
			(start 0.7874 -0.4064)
			(end 0.7874 0.4064)
			(stroke
				(width 0.1524)
				(type default)
			)
			(layer "F.SilkS")
		)
		(fp_line
			(start -0.7874 -0.4064)
			(end 0.7874 -0.4064)
			(stroke
				(width 0.1524)
				(type default)
			)
			(layer "F.SilkS")
		)
		(fp_line
			(start 0.7874 0.4064)
			(end -0.7874 0.4064)
			(stroke
				(width 0.1524)
				(type default)
			)
			(layer "F.SilkS")
		)
		(fp_line
			(start -0.7874 0.4064)
			(end -0.7874 -0.4064)
			(stroke
				(width 0.1524)
				(type default)
			)
			(layer "F.SilkS")
		)
		(fp_line
			(start -0.12065 -0.305054)
			(end -0.12065 -0.2794)
			(stroke
				(width 0.1)
				(type default)
			)
			(layer "F.Fab")
		)
		(fp_line
			(start -0.67945 -0.305054)
			(end -0.12065 -0.305054)
			(stroke
				(width 0.1)
				(type default)
			)
			(layer "F.Fab")
		)
		(fp_line
			(start 0.67945 -0.3048)
			(end 0.67945 0.3048)
			(stroke
				(width 0.1)
				(type default)
			)
			(layer "F.Fab")
		)
		(fp_line
			(start 0.12065 -0.3048)
			(end 0.67945 -0.3048)
			(stroke
				(width 0.1)
				(type default)
			)
			(layer "F.Fab")
		)
		(fp_line
			(start 0.12065 -0.2794)
			(end 0.12065 -0.3048)
			(stroke
				(width 0.1)
				(type default)
			)
			(layer "F.Fab")
		)
		(fp_line
			(start -0.12065 -0.2794)
			(end 0.12065 -0.2794)
			(stroke
				(width 0.1)
				(type default)
			)
			(layer "F.Fab")
		)
		(fp_line
			(start 0.120396 0.2794)
			(end -0.12065 0.2794)
			(stroke
				(width 0.1)
				(type default)
			)
			(layer "F.Fab")
		)
		(fp_line
			(start -0.12065 0.2794)
			(end -0.12065 0.3048)
			(stroke
				(width 0.1)
				(type default)
			)
			(layer "F.Fab")
		)
		(fp_line
			(start 0.67945 0.3048)
			(end 0.120396 0.3048)
			(stroke
				(width 0.1)
				(type default)
			)
			(layer "F.Fab")
		)
		(fp_line
			(start 0.120396 0.3048)
			(end 0.120396 0.2794)
			(stroke
				(width 0.1)
				(type default)
			)
			(layer "F.Fab")
		)
		(fp_line
			(start -0.12065 0.3048)
			(end -0.67945 0.3048)
			(stroke
				(width 0.1)
				(type default)
			)
			(layer "F.Fab")
		)
		(fp_line
			(start -0.67945 0.3048)
			(end -0.67945 -0.305054)
			(stroke
				(width 0.1)
				(type default)
			)
			(layer "F.Fab")
		)
		(pad "1" smd circle
			(at -0.40005 0 90)
			(size 0 0)
			(layers "F.Cu" "F.Mask" "F.Paste")
			(net "PVPP_HBM_CPU1_CS")
		)
		(pad "2" smd circle
			(at 0.40005 0 90)
			(size 0 0)
			(layers "F.Cu" "F.Mask" "F.Paste")
			(net "GND")
		)
	)
	(footprint ""
		(layer "F.Cu")
		(at 62.994032 -143.757904 180)
		(property "Reference" "PC452_P1_1"
			(at 0 0 180)
			(layer "F.SilkS")
			(hide yes)
			(effects
				(font
					(size 1.27 1.27)
				)
			)
		)
		(property "Value" ""
			(at 0 0 180)
			(layer "F.Fab")
			(effects
				(font
					(size 1.27 1.27)
				)
			)
		)
		(duplicate_pad_numbers_are_jumpers no)
		(fp_line
			(start 0.7874 0.4064)
			(end -0.7874 0.4064)
			(stroke
				(width 0.1524)
				(type default)
			)
			(layer "F.SilkS")
		)
		(fp_line
			(start 0.7874 -0.4064)
			(end 0.7874 0.4064)
			(stroke
				(width 0.1524)
				(type default)
			)
			(layer "F.SilkS")
		)
		(fp_line
			(start -0.7874 0.4064)
			(end -0.7874 -0.4064)
			(stroke
				(width 0.1524)
				(type default)
			)
			(layer "F.SilkS")
		)
		(fp_line
			(start -0.7874 -0.4064)
			(end 0.7874 -0.4064)
			(stroke
				(width 0.1524)
				(type default)
			)
			(layer "F.SilkS")
		)
		(fp_line
			(start 0.67945 0.3048)
			(end 0.120396 0.3048)
			(stroke
				(width 0.1)
				(type default)
			)
			(layer "F.Fab")
		)
		(fp_line
			(start 0.67945 -0.3048)
			(end 0.67945 0.3048)
			(stroke
				(width 0.1)
				(type default)
			)
			(layer "F.Fab")
		)
		(fp_line
			(start 0.12065 -0.2794)
			(end 0.12065 -0.3048)
			(stroke
				(width 0.1)
				(type default)
			)
			(layer "F.Fab")
		)
		(fp_line
			(start 0.12065 -0.3048)
			(end 0.67945 -0.3048)
			(stroke
				(width 0.1)
				(type default)
			)
			(layer "F.Fab")
		)
		(fp_line
			(start 0.120396 0.3048)
			(end 0.120396 0.2794)
			(stroke
				(width 0.1)
				(type default)
			)
			(layer "F.Fab")
		)
		(fp_line
			(start 0.120396 0.2794)
			(end -0.12065 0.2794)
			(stroke
				(width 0.1)
				(type default)
			)
			(layer "F.Fab")
		)
		(fp_line
			(start -0.12065 0.3048)
			(end -0.67945 0.3048)
			(stroke
				(width 0.1)
				(type default)
			)
			(layer "F.Fab")
		)
		(fp_line
			(start -0.12065 0.2794)
			(end -0.12065 0.3048)
			(stroke
				(width 0.1)
				(type default)
			)
			(layer "F.Fab")
		)
		(fp_line
			(start -0.12065 -0.2794)
			(end 0.12065 -0.2794)
			(stroke
				(width 0.1)
				(type default)
			)
			(layer "F.Fab")
		)
		(fp_line
			(start -0.12065 -0.305054)
			(end -0.12065 -0.2794)
			(stroke
				(width 0.1)
				(type default)
			)
			(layer "F.Fab")
		)
		(fp_line
			(start -0.67945 0.3048)
			(end -0.67945 -0.305054)
			(stroke
				(width 0.1)
				(type default)
			)
			(layer "F.Fab")
		)
		(fp_line
			(start -0.67945 -0.305054)
			(end -0.12065 -0.305054)
			(stroke
				(width 0.1)
				(type default)
			)
			(layer "F.Fab")
		)
		(pad "1" smd circle
			(at -0.40005 0 180)
			(size 0 0)
			(layers "F.Cu" "F.Mask" "F.Paste")
			(net "PVCCINFAON_CPU1")
		)
		(pad "2" smd circle
			(at 0.40005 0 180)
			(size 0 0)
			(layers "F.Cu" "F.Mask" "F.Paste")
			(net "GND")
		)
	)
)
